# T6G (Grand Teton) — schematic netlist excerpt (pin names and nets, part order shuffled) for the footprints in the layout excerpt that follows; sources: Cadence DE-HDL packaged netlist, KiCad conversion of 04192023_DAF0TMB3IC0_F0TG_MB_C_brd_V02_OCP.brd

R1200  Q_RES  0 5% CHIP  pkg 0201LF  page 186 : A = RST_SMB_RT_ROM_R1_N ; B = FM_SMB_RT_ROM_MUX4_SEL
PC162  Q_CAPP  470UF 2.5V 20% SPCAP  pkg SMLF  page 205 : A = PVDDIO_P0 ; B = GND
R6246  Q_RES  130 1% CHIP  pkg 0402LF  page 254 : A = LED_PWRGD_P1V2_AUX ; B = P3V3_AUX

(kicad_pcb
	(version 20260206)
	(generator "pcbnew")
	(generator_version "10.0")
	(general
		(thickness 1.6)
		(legacy_teardrops no)
	)
	(paper "A4")
	(title_block
		(title "04192023_DAF0TMB3IC0_F0TG_MB_C_brd_V02_OCP.brd")
		(comment 1 "Grand Teton / footprints 7545-7547 of 8354")
	)
	(layers
		(0 "F.Cu" signal "TOP")
		(4 "In1.Cu" signal "GND")
		(6 "In2.Cu" signal "IN1")
		(8 "In3.Cu" signal "GND1")
		(10 "In4.Cu" signal "IN2")
		(12 "In5.Cu" signal "GND2")
		(14 "In6.Cu" signal "IN3")
		(16 "In7.Cu" signal "GND3")
		(18 "In8.Cu" signal "VCC")
		(20 "In9.Cu" signal "VCC1")
		(22 "In10.Cu" signal "GND4")
		(24 "In11.Cu" signal "IN4")
		(26 "In12.Cu" signal "GND5")
		(28 "In13.Cu" signal "IN5")
		(30 "In14.Cu" signal "GND6")
		(32 "In15.Cu" signal "IN6")
		(34 "In16.Cu" signal "GND7")
		(2 "B.Cu" signal "BOTTOM")
		(9 "F.Adhes" user "F.Adhesive")
		(11 "B.Adhes" user "B.Adhesive")
		(13 "F.Paste" user "Package Geometry/Pastemask Top")
		(15 "B.Paste" user "Package Geometry/Pastemask Bottom")
		(5 "F.SilkS" user "Ref Des/Silkscreen Top")
		(7 "B.SilkS" user "Ref Des/Silkscreen Bottom")
		(1 "F.Mask" user "Board Geometry/Soldermask Top")
		(3 "B.Mask" user "Board Geometry/Soldermask Bottom")
		(17 "Dwgs.User" user "User.Drawings")
		(19 "Cmts.User" user "User.Comments")
		(21 "Eco1.User" user "User.Eco1")
		(23 "Eco2.User" user "User.Eco2")
		(25 "Edge.Cuts" user "Board Geometry/Outline")
		(27 "Margin" user)
		(31 "F.CrtYd" user "Package Geometry/Place Bound Top")
		(29 "B.CrtYd" user "Package Geometry/Place Bound Bottom")
		(35 "F.Fab" user "Ref Des/Assembly Top")
		(33 "B.Fab" user "Ref Des/Assembly Bottom")
	)
	(footprint ""
		(layer "B.Cu")
		(at 299.905928 -339.885528 -90)
		(property "Reference" "PC162"
			(at 9.619996 -0.997966 270)
			(unlocked yes)
			(layer "B.SilkS")
			(effects
				(font
					(size 0.7874 0.5842)
					(thickness 0.1524)
				)
				(justify left mirror)
			)
		)
		(property "Value" ""
			(at 0 0 90)
			(layer "B.Fab")
			(effects
				(font
					(size 1.27 1.27)
				)
				(justify mirror)
			)
		)
		(duplicate_pad_numbers_are_jumpers no)
		(fp_line
			(start -4.533392 2.249932)
			(end 4.533392 2.249932)
			(stroke
				(width 0.1524)
				(type default)
			)
			(layer "B.SilkS")
		)
		(fp_line
			(start 4.533392 2.249932)
			(end 4.533392 -2.249932)
			(stroke
				(width 0.1524)
				(type default)
			)
			(layer "B.SilkS")
		)
		(fp_line
			(start -4.533392 -2.249932)
			(end -4.533392 2.249932)
			(stroke
				(width 0.1524)
				(type default)
			)
			(layer "B.SilkS")
		)
		(fp_line
			(start 4.533392 -2.249932)
			(end -4.533392 -2.249932)
			(stroke
				(width 0.1524)
				(type default)
			)
			(layer "B.SilkS")
		)
		(fp_rect
			(start 5.39242 2.326132)
			(end 4.533392 -2.326132)
			(stroke
				(width 0)
				(type default)
			)
			(fill yes)
			(layer "B.SilkS")
		)
		(fp_line
			(start -3.750056 2.249932)
			(end 3.750056 2.249932)
			(stroke
				(width 0.1)
				(type default)
			)
			(layer "B.Fab")
		)
		(fp_line
			(start 3.750056 2.249932)
			(end 3.750056 -2.249932)
			(stroke
				(width 0.1)
				(type default)
			)
			(layer "B.Fab")
		)
		(fp_line
			(start -3.750056 -2.249932)
			(end -3.750056 2.249932)
			(stroke
				(width 0.1)
				(type default)
			)
			(layer "B.Fab")
		)
		(fp_line
			(start 3.750056 -2.249932)
			(end -3.750056 -2.249932)
			(stroke
				(width 0.1)
				(type default)
			)
			(layer "B.Fab")
		)
		(fp_text user "-"
			(at -4.607814 2.00787 270)
			(unlocked yes)
			(layer "B.SilkS")
			(effects
				(font
					(size 1.905 1.4224)
					(thickness 0.1524)
				)
				(justify left mirror)
			)
		)
		(fp_text user "+"
			(at 6.322314 0.786384 180)
			(unlocked yes)
			(layer "B.SilkS")
			(effects
				(font
					(size 1.905 1.4224)
					(thickness 0.1524)
				)
				(justify left mirror)
			)
		)
		(fp_text user "+"
			(at 6.322314 0.786384 180)
			(unlocked yes)
			(layer "B.Fab")
			(effects
				(font
					(size 1.905 1.4224)
					(thickness 0.1524)
				)
				(justify left mirror)
			)
		)
		(fp_text user "-"
			(at -4.8514 -0.14605 270)
			(unlocked yes)
			(layer "B.Fab")
			(effects
				(font
					(size 1.905 1.4224)
					(thickness 0.1524)
				)
				(justify left mirror)
			)
		)
		(pad "1" smd rect
			(at 3.199892 0 90)
			(size 2.413 2.8194)
			(layers "B.Cu" "B.Mask" "B.Paste")
			(net "PVDDIO_P0")
		)
		(pad "2" smd rect
			(at -3.199892 0 90)
			(size 2.413 2.8194)
			(layers "B.Cu" "B.Mask" "B.Paste")
			(net "GND")
		)
	)
	(footprint ""
		(layer "B.Cu")
		(at 308.379876 -66.708782 90)
		(property "Reference" "R6246"
			(at 0 0 90)
			(layer "B.SilkS")
			(hide yes)
			(effects
				(font
					(size 1.27 1.27)
				)
				(justify mirror)
			)
		)
		(property "Value" ""
			(at 0 0 90)
			(layer "B.Fab")
			(effects
				(font
					(size 1.27 1.27)
				)
				(justify mirror)
			)
		)
		(duplicate_pad_numbers_are_jumpers no)
		(fp_line
			(start 0.7874 -0.4064)
			(end -0.7874 -0.4064)
			(stroke
				(width 0.1524)
				(type default)
			)
			(layer "B.SilkS")
		)
		(fp_line
			(start -0.7874 -0.4064)
			(end -0.7874 0.4064)
			(stroke
				(width 0.1524)
				(type default)
			)
			(layer "B.SilkS")
		)
		(fp_line
			(start 0.7874 0.4064)
			(end 0.7874 -0.4064)
			(stroke
				(width 0.1524)
				(type default)
			)
			(layer "B.SilkS")
		)
		(fp_line
			(start -0.7874 0.4064)
			(end 0.7874 0.4064)
			(stroke
				(width 0.1524)
				(type default)
			)
			(layer "B.SilkS")
		)
		(fp_line
			(start 0.67945 -0.305054)
			(end 0.12065 -0.305054)
			(stroke
				(width 0.1)
				(type default)
			)
			(layer "B.Fab")
		)
		(fp_line
			(start 0.12065 -0.305054)
			(end 0.12065 -0.2794)
			(stroke
				(width 0.1)
				(type default)
			)
			(layer "B.Fab")
		)
		(fp_line
			(start -0.12065 -0.3048)
			(end -0.67945 -0.3048)
			(stroke
				(width 0.1)
				(type default)
			)
			(layer "B.Fab")
		)
		(fp_line
			(start -0.67945 -0.3048)
			(end -0.67945 0.3048)
			(stroke
				(width 0.1)
				(type default)
			)
			(layer "B.Fab")
		)
		(fp_line
			(start 0.12065 -0.2794)
			(end -0.12065 -0.2794)
			(stroke
				(width 0.1)
				(type default)
			)
			(layer "B.Fab")
		)
		(fp_line
			(start -0.12065 -0.2794)
			(end -0.12065 -0.3048)
			(stroke
				(width 0.1)
				(type default)
			)
			(layer "B.Fab")
		)
		(fp_line
			(start 0.12065 0.2794)
			(end 0.12065 0.3048)
			(stroke
				(width 0.1)
				(type default)
			)
			(layer "B.Fab")
		)
		(fp_line
			(start -0.120396 0.2794)
			(end 0.12065 0.2794)
			(stroke
				(width 0.1)
				(type default)
			)
			(layer "B.Fab")
		)
		(fp_line
			(start 0.67945 0.3048)
			(end 0.67945 -0.305054)
			(stroke
				(width 0.1)
				(type default)
			)
			(layer "B.Fab")
		)
		(fp_line
			(start 0.12065 0.3048)
			(end 0.67945 0.3048)
			(stroke
				(width 0.1)
				(type default)
			)
			(layer "B.Fab")
		)
		(fp_line
			(start -0.120396 0.3048)
			(end -0.120396 0.2794)
			(stroke
				(width 0.1)
				(type default)
			)
			(layer "B.Fab")
		)
		(fp_line
			(start -0.67945 0.3048)
			(end -0.120396 0.3048)
			(stroke
				(width 0.1)
				(type default)
			)
			(layer "B.Fab")
		)
		(pad "1" smd circle
			(at 0.40005 0 270)
			(size 0 0)
			(layers "B.Cu" "B.Mask" "B.Paste")
			(net "LED_PWRGD_P1V2_AUX")
		)
		(pad "2" smd circle
			(at -0.40005 0 270)
			(size 0 0)
			(layers "B.Cu" "B.Mask" "B.Paste")
			(net "P3V3_AUX")
		)
	)
	(footprint ""
		(layer "B.Cu")
		(at 163.423092 -417.295584)
		(property "Reference" "R1200"
			(at 0 0 0)
			(layer "B.SilkS")
			(hide yes)
			(effects
				(font
					(size 1.27 1.27)
				)
				(justify mirror)
			)
		)
		(property "Value" ""
			(at 0 0 0)
			(layer "B.Fab")
			(effects
				(font
					(size 1.27 1.27)
				)
				(justify mirror)
			)
		)
		(duplicate_pad_numbers_are_jumpers no)
		(fp_line
			(start -0.32512 -0.175006)
			(end -0.32512 0.175006)
			(stroke
				(width 0.1)
				(type default)
			)
			(layer "B.Fab")
		)
		(fp_line
			(start -0.32512 0.175006)
			(end 0.32512 0.175006)
			(stroke
				(width 0.1)
				(type default)
			)
			(layer "B.Fab")
		)
		(fp_line
			(start 0.32512 -0.175006)
			(end -0.32512 -0.175006)
			(stroke
				(width 0.1)
				(type default)
			)
			(layer "B.Fab")
		)
		(fp_line
			(start 0.32512 0.175006)
			(end 0.32512 -0.175006)
			(stroke
				(width 0.1)
				(type default)
			)
			(layer "B.Fab")
		)
		(pad "1" smd rect
			(at 0.2667 0 180)
			(size 0.3048 0.381)
			(layers "B.Cu" "B.Mask" "B.Paste")
			(net "RST_SMB_RT_ROM_R1_N")
		)
		(pad "2" smd rect
			(at -0.2667 0)
			(size 0.3048 0.381)
			(layers "B.Cu" "B.Mask" "B.Paste")
			(net "FM_SMB_RT_ROM_MUX4_SEL")
		)
	)
)
